# T6G (Grand Teton) — schematic netlist excerpt (pin names and nets, part order shuffled) for the footprints in the layout excerpt that follows; sources: Cadence DE-HDL packaged netlist, KiCad conversion of 04192023_DAF0TMB3IC0_F0TG_MB_C_brd_V02_OCP.brd

PR296  Q_RES  49.9 1% CHIP  pkg 0402LF  page 193 : A = PVDDCR_SOC_P0 ; B = VSENSE_PVDDCR_SOC_P0_DP
PR98  Q_RES  8.87K 1% EMPTY  pkg 0402LF  page 205 : A = PVDDIO_P0_LSET1 ; B = GND

(kicad_pcb
	(version 20260206)
	(generator "pcbnew")
	(generator_version "10.0")
	(general
		(thickness 1.6)
		(legacy_teardrops no)
	)
	(paper "A4")
	(title_block
		(title "04192023_DAF0TMB3IC0_F0TG_MB_C_brd_V02_OCP.brd")
		(comment 1 "Grand Teton / footprints 610-611 of 8354")
	)
	(layers
		(0 "F.Cu" signal "TOP")
		(4 "In1.Cu" signal "GND")
		(6 "In2.Cu" signal "IN1")
		(8 "In3.Cu" signal "GND1")
		(10 "In4.Cu" signal "IN2")
		(12 "In5.Cu" signal "GND2")
		(14 "In6.Cu" signal "IN3")
		(16 "In7.Cu" signal "GND3")
		(18 "In8.Cu" signal "VCC")
		(20 "In9.Cu" signal "VCC1")
		(22 "In10.Cu" signal "GND4")
		(24 "In11.Cu" signal "IN4")
		(26 "In12.Cu" signal "GND5")
		(28 "In13.Cu" signal "IN5")
		(30 "In14.Cu" signal "GND6")
		(32 "In15.Cu" signal "IN6")
		(34 "In16.Cu" signal "GND7")
		(2 "B.Cu" signal "BOTTOM")
		(9 "F.Adhes" user "F.Adhesive")
		(11 "B.Adhes" user "B.Adhesive")
		(13 "F.Paste" user "Package Geometry/Pastemask Top")
		(15 "B.Paste" user "Package Geometry/Pastemask Bottom")
		(5 "F.SilkS" user "Ref Des/Silkscreen Top")
		(7 "B.SilkS" user "Ref Des/Silkscreen Bottom")
		(1 "F.Mask" user "Board Geometry/Soldermask Top")
		(3 "B.Mask" user "Board Geometry/Soldermask Bottom")
		(17 "Dwgs.User" user "User.Drawings")
		(19 "Cmts.User" user "User.Comments")
		(21 "Eco1.User" user "User.Eco1")
		(23 "Eco2.User" user "User.Eco2")
		(25 "Edge.Cuts" user "Board Geometry/Outline")
		(27 "Margin" user)
		(31 "F.CrtYd" user "Package Geometry/Place Bound Top")
		(29 "B.CrtYd" user "Package Geometry/Place Bound Bottom")
		(35 "F.Fab" user "Ref Des/Assembly Top")
		(33 "B.Fab" user "Ref Des/Assembly Bottom")
	)
	(footprint ""
		(layer "F.Cu")
		(at 421.174164 -176.864772)
		(property "Reference" "PR296"
			(at 0 0 0)
			(layer "F.SilkS")
			(hide yes)
			(effects
				(font
					(size 1.27 1.27)
				)
			)
		)
		(property "Value" ""
			(at 0 0 0)
			(layer "F.Fab")
			(effects
				(font
					(size 1.27 1.27)
				)
			)
		)
		(duplicate_pad_numbers_are_jumpers no)
		(fp_line
			(start -0.7874 -0.4064)
			(end 0.7874 -0.4064)
			(stroke
				(width 0.1524)
				(type default)
			)
			(layer "F.SilkS")
		)
		(fp_line
			(start -0.7874 0.4064)
			(end -0.7874 -0.4064)
			(stroke
				(width 0.1524)
				(type default)
			)
			(layer "F.SilkS")
		)
		(fp_line
			(start 0.7874 -0.4064)
			(end 0.7874 0.4064)
			(stroke
				(width 0.1524)
				(type default)
			)
			(layer "F.SilkS")
		)
		(fp_line
			(start 0.7874 0.4064)
			(end -0.7874 0.4064)
			(stroke
				(width 0.1524)
				(type default)
			)
			(layer "F.SilkS")
		)
		(fp_line
			(start -0.67945 -0.305054)
			(end -0.12065 -0.305054)
			(stroke
				(width 0.1)
				(type default)
			)
			(layer "F.Fab")
		)
		(fp_line
			(start -0.67945 0.3048)
			(end -0.67945 -0.305054)
			(stroke
				(width 0.1)
				(type default)
			)
			(layer "F.Fab")
		)
		(fp_line
			(start -0.12065 -0.305054)
			(end -0.12065 -0.2794)
			(stroke
				(width 0.1)
				(type default)
			)
			(layer "F.Fab")
		)
		(fp_line
			(start -0.12065 -0.2794)
			(end 0.12065 -0.2794)
			(stroke
				(width 0.1)
				(type default)
			)
			(layer "F.Fab")
		)
		(fp_line
			(start -0.12065 0.2794)
			(end -0.12065 0.3048)
			(stroke
				(width 0.1)
				(type default)
			)
			(layer "F.Fab")
		)
		(fp_line
			(start -0.12065 0.3048)
			(end -0.67945 0.3048)
			(stroke
				(width 0.1)
				(type default)
			)
			(layer "F.Fab")
		)
		(fp_line
			(start 0.120396 0.2794)
			(end -0.12065 0.2794)
			(stroke
				(width 0.1)
				(type default)
			)
			(layer "F.Fab")
		)
		(fp_line
			(start 0.120396 0.3048)
			(end 0.120396 0.2794)
			(stroke
				(width 0.1)
				(type default)
			)
			(layer "F.Fab")
		)
		(fp_line
			(start 0.12065 -0.3048)
			(end 0.67945 -0.3048)
			(stroke
				(width 0.1)
				(type default)
			)
			(layer "F.Fab")
		)
		(fp_line
			(start 0.12065 -0.2794)
			(end 0.12065 -0.3048)
			(stroke
				(width 0.1)
				(type default)
			)
			(layer "F.Fab")
		)
		(fp_line
			(start 0.67945 -0.3048)
			(end 0.67945 0.3048)
			(stroke
				(width 0.1)
				(type default)
			)
			(layer "F.Fab")
		)
		(fp_line
			(start 0.67945 0.3048)
			(end 0.120396 0.3048)
			(stroke
				(width 0.1)
				(type default)
			)
			(layer "F.Fab")
		)
		(pad "1" smd circle
			(at -0.40005 0)
			(size 0 0)
			(layers "F.Cu" "F.Mask" "F.Paste")
			(net "PVDDCR_SOC_P0")
		)
		(pad "2" smd circle
			(at 0.40005 0)
			(size 0 0)
			(layers "F.Cu" "F.Mask" "F.Paste")
			(net "VSENSE_PVDDCR_SOC_P0_DP")
		)
	)
	(footprint ""
		(layer "F.Cu")
		(at 299.060362 -351.927922)
		(property "Reference" "PR98"
			(at 0 0 0)
			(layer "F.SilkS")
			(hide yes)
			(effects
				(font
					(size 1.27 1.27)
				)
			)
		)
		(property "Value" ""
			(at 0 0 0)
			(layer "F.Fab")
			(effects
				(font
					(size 1.27 1.27)
				)
			)
		)
		(duplicate_pad_numbers_are_jumpers no)
		(fp_line
			(start -0.7874 -0.4064)
			(end 0.7874 -0.4064)
			(stroke
				(width 0.1524)
				(type default)
			)
			(layer "F.SilkS")
		)
		(fp_line
			(start -0.7874 0.4064)
			(end -0.7874 -0.4064)
			(stroke
				(width 0.1524)
				(type default)
			)
			(layer "F.SilkS")
		)
		(fp_line
			(start 0.7874 -0.4064)
			(end 0.7874 0.4064)
			(stroke
				(width 0.1524)
				(type default)
			)
			(layer "F.SilkS")
		)
		(fp_line
			(start 0.7874 0.4064)
			(end -0.7874 0.4064)
			(stroke
				(width 0.1524)
				(type default)
			)
			(layer "F.SilkS")
		)
		(fp_line
			(start -0.67945 -0.305054)
			(end -0.12065 -0.305054)
			(stroke
				(width 0.1)
				(type default)
			)
			(layer "F.Fab")
		)
		(fp_line
			(start -0.67945 0.3048)
			(end -0.67945 -0.305054)
			(stroke
				(width 0.1)
				(type default)
			)
			(layer "F.Fab")
		)
		(fp_line
			(start -0.12065 -0.305054)
			(end -0.12065 -0.2794)
			(stroke
				(width 0.1)
				(type default)
			)
			(layer "F.Fab")
		)
		(fp_line
			(start -0.12065 -0.2794)
			(end 0.12065 -0.2794)
			(stroke
				(width 0.1)
				(type default)
			)
			(layer "F.Fab")
		)
		(fp_line
			(start -0.12065 0.2794)
			(end -0.12065 0.3048)
			(stroke
				(width 0.1)
				(type default)
			)
			(layer "F.Fab")
		)
		(fp_line
			(start -0.12065 0.3048)
			(end -0.67945 0.3048)
			(stroke
				(width 0.1)
				(type default)
			)
			(layer "F.Fab")
		)
		(fp_line
			(start 0.120396 0.2794)
			(end -0.12065 0.2794)
			(stroke
				(width 0.1)
				(type default)
			)
			(layer "F.Fab")
		)
		(fp_line
			(start 0.120396 0.3048)
			(end 0.120396 0.2794)
			(stroke
				(width 0.1)
				(type default)
			)
			(layer "F.Fab")
		)
		(fp_line
			(start 0.12065 -0.3048)
			(end 0.67945 -0.3048)
			(stroke
				(width 0.1)
				(type default)
			)
			(layer "F.Fab")
		)
		(fp_line
			(start 0.12065 -0.2794)
			(end 0.12065 -0.3048)
			(stroke
				(width 0.1)
				(type default)
			)
			(layer "F.Fab")
		)
		(fp_line
			(start 0.67945 -0.3048)
			(end 0.67945 0.3048)
			(stroke
				(width 0.1)
				(type default)
			)
			(layer "F.Fab")
		)
		(fp_line
			(start 0.67945 0.3048)
			(end 0.120396 0.3048)
			(stroke
				(width 0.1)
				(type default)
			)
			(layer "F.Fab")
		)
		(pad "1" smd circle
			(at -0.40005 0)
			(size 0 0)
			(layers "F.Cu" "F.Mask" "F.Paste")
			(net "PVDDIO_P0_LSET1")
		)
		(pad "2" smd circle
			(at 0.40005 0)
			(size 0 0)
			(layers "F.Cu" "F.Mask" "F.Paste")
			(net "GND")
		)
	)
)
